(kicad_pcb
	(version 20260206)
	(generator "pcbnew")
	(generator_version "10.0")
	(general
		(thickness 1.21888)
		(legacy_teardrops no)
	)
	(paper "A4")
	(title_block
		(title "timecard-v9 — TimeCard-DC-V9_EXP.PcbDoc")
		(comment 1 "Time Appliance Project (Time Card) / footprints 1-6 of 402")
	)
	(layers
		(0 "F.Cu" signal "TOP")
		(4 "In1.Cu" signal "SGND")
		(6 "In2.Cu" signal "IN1")
		(8 "In3.Cu" signal "IN2")
		(10 "In4.Cu" signal "SGND1")
		(2 "B.Cu" signal "BOTTOM")
		(9 "F.Adhes" user "F.Adhesive")
		(11 "B.Adhes" user "B.Adhesive")
		(13 "F.Paste" user "Top Paste")
		(15 "B.Paste" user "Bottom Paste")
		(5 "F.SilkS" user "Top Overlay")
		(7 "B.SilkS" user "Bottom Overlay")
		(1 "F.Mask" user "Top Solder")
		(3 "B.Mask" user "Bottom Solder")
		(17 "Dwgs.User" user "User.Drawings")
		(19 "Cmts.User" user "User.Comments")
		(21 "Eco1.User" user "User.Eco1")
		(23 "Eco2.User" user "User.Eco2")
		(25 "Edge.Cuts" user)
		(27 "Margin" user)
		(31 "F.CrtYd" user "Top Courtyard")
		(29 "B.CrtYd" user "Bottom Courtyard")
		(35 "F.Fab" user "Top Component Center")
		(33 "B.Fab" user "Bottom Component Center")
	)
	(footprint "Vault:SMTC-TSW-105-05-X-S"
		(layer "F.Cu")
		(at 147.8216 94.6162 90)
		(property "Reference" "P1"
			(at 2.808605 -1.973079 90)
			(unlocked yes)
			(layer "F.SilkS")
			(effects
				(font
					(size 0.762 0.762)
					(thickness 0.2286)
				)
			)
		)
		(property "Value" "TSW-105-05-L-S"
			(at -2.910071 6.360355 0)
			(unlocked yes)
			(layer "F.SilkS")
			(hide yes)
			(effects
				(font
					(size 0.762 0.762)
					(thickness 0.2286)
				)
			)
		)
		(sheetname "05-GPS_IMU_SENSORS")
		(sheetfile "05-GPS_IMU_SENSORS.kicad_sch")
		(duplicate_pad_numbers_are_jumpers no)
		(fp_line
			(start 11.62 -1.27)
			(end 11.62 1.27)
			(stroke
				(width 0.2)
				(type solid)
			)
			(layer "F.SilkS")
		)
		(fp_line
			(start -1.46 -1.27)
			(end 11.62 -1.27)
			(stroke
				(width 0.2)
				(type solid)
			)
			(layer "F.SilkS")
		)
		(fp_line
			(start -1.46 -1.27)
			(end -1.46 1.27)
			(stroke
				(width 0.2)
				(type solid)
			)
			(layer "F.SilkS")
		)
		(fp_line
			(start -1.46 1.27)
			(end 11.62 1.27)
			(stroke
				(width 0.2)
				(type solid)
			)
			(layer "F.SilkS")
		)
		(pad "1" thru_hole rect
			(at 0 0 90)
			(size 1.55 1.55)
			(drill 1.02)
			(layers "*.Cu" "*.Mask")
			(remove_unused_layers no)
			(net "+3.3V")
		)
		(pad "2" thru_hole circle
			(at 2.54 0 90)
			(size 1.55 1.55)
			(drill 1.02)
			(layers "*.Cu" "*.Mask")
			(remove_unused_layers no)
			(net "GND")
			(thermal_bridge_angle 90)
		)
		(pad "3" thru_hole circle
			(at 5.08 0 90)
			(size 1.55 1.55)
			(drill 1.02)
			(layers "*.Cu" "*.Mask")
			(remove_unused_layers no)
			(net "ANADC_I2C_SCL")
			(thermal_bridge_angle 90)
		)
		(pad "4" thru_hole circle
			(at 7.62 0 90)
			(size 1.55 1.55)
			(drill 1.02)
			(layers "*.Cu" "*.Mask")
			(remove_unused_layers no)
			(net "ANADC_I2C_SDA")
			(thermal_bridge_angle 90)
		)
		(pad "5" thru_hole circle
			(at 10.16 0 90)
			(size 1.55 1.55)
			(drill 1.02)
			(layers "*.Cu" "*.Mask")
			(remove_unused_layers no)
			(net "NetP1_5")
			(thermal_bridge_angle 90)
		)
	)
	(footprint "Vault:RESC1005X40X25NL05T05"
		(layer "F.Cu")
		(at 166.7216 116.4162)
		(property "Reference" "R127"
			(at -2.3968 0.226921 0)
			(unlocked yes)
			(layer "F.SilkS")
			(effects
				(font
					(size 0.762 0.762)
					(thickness 0.2032)
				)
			)
		)
		(property "Value" "27_1%_0402"
			(at -2.732281 7.35092 270)
			(unlocked yes)
			(layer "F.SilkS")
			(hide yes)
			(effects
				(font
					(size 0.762 0.762)
					(thickness 0.2032)
				)
			)
		)
		(sheetname "08-DIPSwitches_I2C")
		(sheetfile "08-DIPSwitches_I2C.kicad_sch")
		(duplicate_pad_numbers_are_jumpers no)
		(pad "1" smd rect
			(at -0.45 0 90)
			(size 0.55 0.55)
			(layers "F.Cu" "F.Mask" "F.Paste")
			(net "GND")
		)
		(pad "2" smd rect
			(at 0.45 0 90)
			(size 0.55 0.55)
			(layers "F.Cu" "F.Mask" "F.Paste")
			(net "NetR127_2")
		)
	)
	(footprint "Vault:FP-LTST-C191KGKT-MFG"
		(layer "F.Cu")
		(at 224.7216 112.7162)
		(property "Reference" "D22"
			(at -3.44522 0.026921 0)
			(unlocked yes)
			(layer "F.SilkS")
			(effects
				(font
					(size 0.762 0.762)
					(thickness 0.2286)
				)
			)
		)
		(property "Value" "LTST-C191KGKT"
			(at -3.697471 8.34107 270)
			(unlocked yes)
			(layer "F.SilkS")
			(hide yes)
			(effects
				(font
					(size 0.762 0.762)
					(thickness 0.2286)
				)
			)
		)
		(sheetname "08-DIPSwitches_I2C")
		(sheetfile "08-DIPSwitches_I2C.kicad_sch")
		(duplicate_pad_numbers_are_jumpers no)
		(fp_line
			(start -0.85 -0.775)
			(end 0.85 -0.775)
			(stroke
				(width 0.2)
				(type solid)
			)
			(layer "F.SilkS")
		)
		(fp_line
			(start -0.85 0.775)
			(end 0.85 0.775)
			(stroke
				(width 0.2)
				(type solid)
			)
			(layer "F.SilkS")
		)
		(fp_circle
			(center -1.7 0)
			(end -1.7 -0.125)
			(stroke
				(width 0.25)
				(type solid)
			)
			(fill no)
			(layer "F.SilkS")
		)
		(fp_line
			(start -1.25 -0.55)
			(end 1.25 -0.55)
			(stroke
				(width 0.2)
				(type solid)
			)
			(layer "F.CrtYd")
		)
		(fp_line
			(start -1.25 0.55)
			(end -1.25 -0.55)
			(stroke
				(width 0.2)
				(type solid)
			)
			(layer "F.CrtYd")
		)
		(fp_line
			(start -1.25 0.55)
			(end 1.25 0.55)
			(stroke
				(width 0.2)
				(type solid)
			)
			(layer "F.CrtYd")
		)
		(fp_line
			(start 1.25 0.55)
			(end 1.25 -0.55)
			(stroke
				(width 0.2)
				(type solid)
			)
			(layer "F.CrtYd")
		)
		(fp_line
			(start -1.25 -0.55)
			(end 1.25 -0.55)
			(stroke
				(width 0.2)
				(type solid)
			)
			(layer "F.Fab")
		)
		(fp_line
			(start -1.25 0.55)
			(end -1.25 -0.55)
			(stroke
				(width 0.2)
				(type solid)
			)
			(layer "F.Fab")
		)
		(fp_line
			(start -1.25 0.55)
			(end 1.25 0.55)
			(stroke
				(width 0.2)
				(type solid)
			)
			(layer "F.Fab")
		)
		(fp_line
			(start -0.5 0)
			(end 0.5 0)
			(stroke
				(width 0.1)
				(type solid)
			)
			(layer "F.Fab")
		)
		(fp_line
			(start 0 0.5)
			(end 0 -0.5)
			(stroke
				(width 0.1)
				(type solid)
			)
			(layer "F.Fab")
		)
		(fp_line
			(start 1.25 0.55)
			(end 1.25 -0.55)
			(stroke
				(width 0.2)
				(type solid)
			)
			(layer "F.Fab")
		)
		(fp_text user "${REFERENCE}"
			(at 0 0.29534 360)
			(unlocked yes)
			(layer "F.Fab")
			(effects
				(font
					(face "Arial")
					(size 0.63 0.63)
					(thickness 0.1)
				)
				(justify left bottom)
			)
		)
		(pad "1" smd rect
			(at -0.75 0)
			(size 0.8 0.8)
			(layers "F.Cu" "F.Mask" "F.Paste")
			(net "NetD22_1")
			(solder_mask_margin 0)
			(solder_paste_margin 0)
		)
		(pad "2" smd rect
			(at 0.75 0)
			(size 0.8 0.8)
			(layers "F.Cu" "F.Mask" "F.Paste")
			(net "+3.3V")
			(solder_mask_margin 0)
			(solder_paste_margin 0)
		)
	)
	(footprint "Vault:FP-0402-L_1_0_1-W_0_5_0_1-IPC_C"
		(layer "F.Cu")
		(at 171.34767 83.56164 90)
		(property "Reference" "C83"
			(at 1.91684 0.246999 270)
			(unlocked yes)
			(layer "F.SilkS")
			(effects
				(font
					(size 0.762 0.762)
					(thickness 0.2286)
				)
			)
		)
		(property "Value" "0.1uF_25V_0402"
			(at -2.465561 9.839205 0)
			(unlocked yes)
			(layer "F.SilkS")
			(hide yes)
			(effects
				(font
					(size 0.762 0.762)
					(thickness 0.2286)
				)
			)
		)
		(sheetname "03-POWER")
		(sheetfile "03-POWER.kicad_sch")
		(duplicate_pad_numbers_are_jumpers no)
		(fp_line
			(start -0.65607 -0.7)
			(end 0.65606 -0.7)
			(stroke
				(width 0.2)
				(type solid)
			)
			(layer "F.SilkS")
		)
		(fp_line
			(start -0.65607 0.7)
			(end 0.65606 0.7)
			(stroke
				(width 0.2)
				(type solid)
			)
			(layer "F.SilkS")
		)
		(fp_line
			(start 0.75606 -0.4)
			(end 0.75606 0.4)
			(stroke
				(width 0.2)
				(type solid)
			)
			(layer "F.CrtYd")
		)
		(fp_line
			(start -0.75607 -0.4)
			(end 0.75606 -0.4)
			(stroke
				(width 0.2)
				(type solid)
			)
			(layer "F.CrtYd")
		)
		(fp_line
			(start -0.75607 -0.4)
			(end -0.75607 0.4)
			(stroke
				(width 0.2)
				(type solid)
			)
			(layer "F.CrtYd")
		)
		(fp_line
			(start -0.75607 0.4)
			(end 0.75606 0.4)
			(stroke
				(width 0.2)
				(type solid)
			)
			(layer "F.CrtYd")
		)
		(fp_line
			(start 0 -0.5)
			(end 0 0.5)
			(stroke
				(width 0.1)
				(type solid)
			)
			(layer "F.Fab")
		)
		(fp_line
			(start 0.75606 -0.4)
			(end 0.75606 0.4)
			(stroke
				(width 0.2)
				(type solid)
			)
			(layer "F.Fab")
		)
		(fp_line
			(start -0.75607 -0.4)
			(end 0.75606 -0.4)
			(stroke
				(width 0.2)
				(type solid)
			)
			(layer "F.Fab")
		)
		(fp_line
			(start -0.75607 -0.4)
			(end -0.75607 0.4)
			(stroke
				(width 0.2)
				(type solid)
			)
			(layer "F.Fab")
		)
		(fp_line
			(start -0.5 0)
			(end 0.49999 0)
			(stroke
				(width 0.1)
				(type solid)
			)
			(layer "F.Fab")
		)
		(fp_line
			(start -0.75607 0.4)
			(end 0.75606 0.4)
			(stroke
				(width 0.2)
				(type solid)
			)
			(layer "F.Fab")
		)
		(fp_text user "${REFERENCE}"
			(at -0.00002 0.09601 90)
			(unlocked yes)
			(layer "F.Fab")
			(effects
				(font
					(face "Arial")
					(size 0.63 0.63)
					(thickness 0.1)
				)
				(justify left bottom)
			)
		)
		(pad "1" smd rect
			(at -0.36554 0 90)
			(size 0.58106 0.51213)
			(layers "F.Cu" "F.Mask" "F.Paste")
			(net "+3.3V")
			(solder_mask_margin 0)
			(solder_paste_margin 0)
		)
		(pad "2" smd rect
			(at 0.36553 0 90)
			(size 0.58106 0.51213)
			(layers "F.Cu" "F.Mask" "F.Paste")
			(net "GND")
			(solder_mask_margin 0)
			(solder_paste_margin 0)
		)
	)
	(footprint "Vault:RESC1005X40X25LL05T10"
		(layer "F.Cu")
		(at 106.5216 57.6162 180)
		(property "Reference" "R152"
			(at 2.213 0.082179 0)
			(unlocked yes)
			(layer "F.SilkS")
			(effects
				(font
					(size 0.762 0.762)
					(thickness 0.2032)
				)
			)
		)
		(property "Value" "49.9_1%_0402"
			(at -2.579871 8.798275 90)
			(unlocked yes)
			(layer "F.SilkS")
			(hide yes)
			(effects
				(font
					(size 0.762 0.762)
					(thickness 0.2032)
				)
			)
		)
		(sheetname "11-M2_RCB_MUX")
		(sheetfile "11-M2_RCB_MUX.kicad_sch")
		(duplicate_pad_numbers_are_jumpers no)
		(pad "1" smd rect
			(at -0.375 0 270)
			(size 0.45 0.5)
			(layers "F.Cu" "F.Mask" "F.Paste")
			(net "NetR152_1")
		)
		(pad "2" smd rect
			(at 0.375 0 270)
			(size 0.45 0.5)
			(layers "F.Cu" "F.Mask" "F.Paste")
			(net "GPS1_RX")
		)
	)
	(footprint "Resistors:RESC2012X50N"
		(layer "F.Cu")
		(at 184.10761 145.49763)
		(property "Reference" "R18"
			(at -0.68526 -1.068085 0)
			(unlocked yes)
			(layer "F.SilkS")
			(effects
				(font
					(size 0.762 0.762)
					(thickness 0.2286)
				)
				(justify left bottom)
			)
		)
		(property "Value" "CRCW080533R0FKEA"
			(at -5.52491 -8.929165 0)
			(unlocked yes)
			(layer "F.SilkS")
			(hide yes)
			(effects
				(font
					(size 0.762 0.762)
					(thickness 0.2286)
				)
				(justify left bottom)
			)
		)
		(sheetname "04-PCIe_JTAG")
		(sheetfile "04-PCIe_JTAG.kicad_sch")
		(duplicate_pad_numbers_are_jumpers no)
		(fp_line
			(start 0 0.762)
			(end 0 -0.762)
			(stroke
				(width 0.1524)
				(type solid)
			)
			(layer "F.SilkS")
		)
		(pad "1" smd rect
			(at -1 0 90)
			(size 1.45 0.95)
			(layers "F.Cu" "F.Mask" "F.Paste")
			(net "FPGA_TCK")
		)
		(pad "2" smd rect
			(at 1 0 90)
			(size 1.45 0.95)
			(layers "F.Cu" "F.Mask" "F.Paste")
			(net "NetP4_1")
		)
	)
)
